# T6G (Grand Teton) — schematic netlist excerpt (pin names and nets, part order shuffled) for the footprints in the layout excerpt that follows; sources: Cadence DE-HDL packaged netlist, KiCad conversion of 04192023_DAF0TMB3IC0_F0TG_MB_C_brd_V02_OCP.brd

PU16  ISL99390FRZTR5935  ISL99390FRZ-TR5935 IC  pkg QFN21_6X5XB  page 203
  VOS  = PVDDCR_CPU1_P0_VOS5
  AGND  = GND
  VCC  = PVDDCR_CPU1_P0_VCC5
  PVCC  = PVDDCR_CPU1_P0_PVCC
  PGND1  = GND
  GL1  = NC_PVDDCR_CPU1_P0_GL1_5
  PGND2  = GND
  SW  = SW_PVDDCR_CPU1_P0_SW5
  VIN1  = SW_P12V_AUX_PVDDCR_CPU1_P0_FLT
  VIN2  = SW_P12V_AUX_PVDDCR_CPU1_P0_FLT
  DNC  = NC_PVDDCR_CPU1_P0_DNC5
  PHASE  = SW_PVDDCR_CPU1_P0_BOOTR5
  BOOT  = SW_PVDDCR_CPU1_P0_BOOT5
  PWM  = PVDDCR_CPU1_P0_PWM5
  EN  = PVDDCR_CPU1_P0_VCC5
  TOUT_FLT  = PVDDCR_CPU1_P0_TEMP0
  LSET  = PVDDCR_CPU1_P0_LSET5
  IOUT  = PVDDCR_CPU1_P0_IMON5
  REFIN  = PVDDCR_CPU1_P0_VCCS
  PGND3  = GND
  GL2  = NC_PVDDCR_CPU1_P0_GL2_5

(kicad_pcb
	(version 20260206)
	(generator "pcbnew")
	(generator_version "10.0")
	(general
		(thickness 1.6)
		(legacy_teardrops no)
	)
	(paper "A4")
	(title_block
		(title "04192023_DAF0TMB3IC0_F0TG_MB_C_brd_V02_OCP.brd")
		(comment 1 "Grand Teton / footprints 3768-3768 of 8354")
	)
	(layers
		(0 "F.Cu" signal "TOP")
		(4 "In1.Cu" signal "GND")
		(6 "In2.Cu" signal "IN1")
		(8 "In3.Cu" signal "GND1")
		(10 "In4.Cu" signal "IN2")
		(12 "In5.Cu" signal "GND2")
		(14 "In6.Cu" signal "IN3")
		(16 "In7.Cu" signal "GND3")
		(18 "In8.Cu" signal "VCC")
		(20 "In9.Cu" signal "VCC1")
		(22 "In10.Cu" signal "GND4")
		(24 "In11.Cu" signal "IN4")
		(26 "In12.Cu" signal "GND5")
		(28 "In13.Cu" signal "IN5")
		(30 "In14.Cu" signal "GND6")
		(32 "In15.Cu" signal "IN6")
		(34 "In16.Cu" signal "GND7")
		(2 "B.Cu" signal "BOTTOM")
		(9 "F.Adhes" user "F.Adhesive")
		(11 "B.Adhes" user "B.Adhesive")
		(13 "F.Paste" user "Package Geometry/Pastemask Top")
		(15 "B.Paste" user "Package Geometry/Pastemask Bottom")
		(5 "F.SilkS" user "Ref Des/Silkscreen Top")
		(7 "B.SilkS" user "Ref Des/Silkscreen Bottom")
		(1 "F.Mask" user "Board Geometry/Soldermask Top")
		(3 "B.Mask" user "Board Geometry/Soldermask Bottom")
		(17 "Dwgs.User" user "User.Drawings")
		(19 "Cmts.User" user "User.Comments")
		(21 "Eco1.User" user "User.Eco1")
		(23 "Eco2.User" user "User.Eco2")
		(25 "Edge.Cuts" user "Board Geometry/Outline")
		(27 "Margin" user)
		(31 "F.CrtYd" user "Package Geometry/Place Bound Top")
		(29 "B.CrtYd" user "Package Geometry/Place Bound Bottom")
		(35 "F.Fab" user "Ref Des/Assembly Top")
		(33 "B.Fab" user "Ref Des/Assembly Bottom")
	)
	(footprint ""
		(layer "F.Cu")
		(at 343.39022 -335.024476)
		(property "Reference" "PU16"
			(at -3.03022 -7.848854 0)
			(unlocked yes)
			(layer "F.SilkS")
			(effects
				(font
					(size 0.7874 0.5842)
					(thickness 0.1524)
				)
				(justify left)
			)
		)
		(property "Value" ""
			(at 0 0 0)
			(layer "F.Fab")
			(effects
				(font
					(size 1.27 1.27)
				)
			)
		)
		(duplicate_pad_numbers_are_jumpers no)
		(fp_line
			(start -2.500122 -2.999994)
			(end -2.24409 -2.999994)
			(stroke
				(width 0.1524)
				(type default)
			)
			(layer "F.SilkS")
		)
		(fp_line
			(start -2.500122 -2.529078)
			(end -2.500122 -2.999994)
			(stroke
				(width 0.1524)
				(type default)
			)
			(layer "F.SilkS")
		)
		(fp_line
			(start -2.500122 0.6604)
			(end -2.500122 0.229108)
			(stroke
				(width 0.1524)
				(type default)
			)
			(layer "F.SilkS")
		)
		(fp_line
			(start -2.500122 2.999994)
			(end -2.500122 2.339594)
			(stroke
				(width 0.1524)
				(type default)
			)
			(layer "F.SilkS")
		)
		(fp_line
			(start -2.2987 2.999994)
			(end -2.500122 2.999994)
			(stroke
				(width 0.1524)
				(type default)
			)
			(layer "F.SilkS")
		)
		(fp_line
			(start 2.31394 -2.999994)
			(end 2.500122 -2.999994)
			(stroke
				(width 0.1524)
				(type default)
			)
			(layer "F.SilkS")
		)
		(fp_line
			(start 2.500122 -2.999994)
			(end 2.500122 -2.44348)
			(stroke
				(width 0.1524)
				(type default)
			)
			(layer "F.SilkS")
		)
		(fp_line
			(start 2.500122 2.339594)
			(end 2.500122 2.999994)
			(stroke
				(width 0.1524)
				(type default)
			)
			(layer "F.SilkS")
		)
		(fp_line
			(start 2.500122 2.999994)
			(end 2.2987 2.999994)
			(stroke
				(width 0.1524)
				(type default)
			)
			(layer "F.SilkS")
		)
		(fp_poly
			(pts
				(xy -2.742692 -2.464308) (xy -3.4163 -2.68859) (xy -2.967228 -3.137662)
			)
			(stroke
				(width 0)
				(type default)
			)
			(fill yes)
			(layer "F.SilkS")
		)
		(fp_line
			(start -2.500122 -2.999994)
			(end 2.500122 -2.999994)
			(stroke
				(width 0.1)
				(type default)
			)
			(layer "F.Fab")
		)
		(fp_line
			(start -2.500122 2.999994)
			(end -2.500122 -2.999994)
			(stroke
				(width 0.1)
				(type default)
			)
			(layer "F.Fab")
		)
		(fp_line
			(start 2.500122 -2.999994)
			(end 2.500122 2.999994)
			(stroke
				(width 0.1)
				(type default)
			)
			(layer "F.Fab")
		)
		(fp_line
			(start 2.500122 2.999994)
			(end -2.500122 2.999994)
			(stroke
				(width 0.1)
				(type default)
			)
			(layer "F.Fab")
		)
		(fp_poly
			(pts
				(xy -4.218432 -2.783078) (xy -4.218432 -1.767078) (xy -3.202432 -2.275078)
			)
			(stroke
				(width 0)
				(type default)
			)
			(fill yes)
			(layer "F.Fab")
		)
		(pad "1" smd rect
			(at -2.400046 -2.275078 90)
			(size 0.2286 0.6096)
			(layers "F.Cu" "F.Mask" "F.Paste")
			(net "PVDDCR_CPU1_P0_VOS5")
		)
		(pad "2" smd rect
			(at -2.400046 -1.82499 90)
			(size 0.2286 0.6096)
			(layers "F.Cu" "F.Mask" "F.Paste")
			(net "GND")
		)
		(pad "3" smd rect
			(at -2.400046 -1.374902 90)
			(size 0.2286 0.6096)
			(layers "F.Cu" "F.Mask" "F.Paste")
			(net "PVDDCR_CPU1_P0_VCC5")
		)
		(pad "4" smd rect
			(at -2.400046 -0.925068 90)
			(size 0.2286 0.6096)
			(layers "F.Cu" "F.Mask" "F.Paste")
			(net "PVDDCR_CPU1_P0_PVCC")
		)
		(pad "5" smd rect
			(at -2.400046 -0.47498 90)
			(size 0.2286 0.6096)
			(layers "F.Cu" "F.Mask" "F.Paste")
			(net "GND")
		)
		(pad "6" smd rect
			(at -2.400046 -0.024892 90)
			(size 0.2286 0.6096)
			(layers "F.Cu" "F.Mask" "F.Paste")
			(net "NC_PVDDCR_CPU1_P0_GL1_5")
		)
		(pad "7_9-20_24" smd circle
			(at 0 1.150112 90)
			(size 0 0)
			(layers "F.Cu" "F.Mask" "F.Paste")
			(net "GND")
		)
		(pad "10_19" smd rect
			(at 0 2.899918 90)
			(size 0.6096 4.318)
			(layers "F.Cu" "F.Mask" "F.Paste")
			(net "SW_PVDDCR_CPU1_P0_SW5")
		)
		(pad "25_29" smd rect
			(at 1.549908 -1.279906 270)
			(size 2.0574 2.3114)
			(layers "F.Cu" "F.Mask" "F.Paste")
			(net "SW_P12V_AUX_PVDDCR_CPU1_P0_FLT")
		)
		(pad "30" smd rect
			(at 2.05994 -2.899918)
			(size 0.2286 0.6096)
			(layers "F.Cu" "F.Mask" "F.Paste")
			(net "SW_P12V_AUX_PVDDCR_CPU1_P0_FLT")
		)
		(pad "31" smd rect
			(at 1.610106 -2.899918)
			(size 0.2286 0.6096)
			(layers "F.Cu" "F.Mask" "F.Paste")
			(net "NC_PVDDCR_CPU1_P0_DNC5")
		)
		(pad "32" smd rect
			(at 1.160018 -2.899918)
			(size 0.2286 0.6096)
			(layers "F.Cu" "F.Mask" "F.Paste")
			(net "SW_PVDDCR_CPU1_P0_BOOTR5")
		)
		(pad "33" smd rect
			(at 0.70993 -2.899918)
			(size 0.2286 0.6096)
			(layers "F.Cu" "F.Mask" "F.Paste")
			(net "SW_PVDDCR_CPU1_P0_BOOT5")
		)
		(pad "34" smd rect
			(at 0.260096 -2.899918)
			(size 0.2286 0.6096)
			(layers "F.Cu" "F.Mask" "F.Paste")
			(net "PVDDCR_CPU1_P0_PWM5")
		)
		(pad "35" smd rect
			(at -0.189992 -2.899918)
			(size 0.2286 0.6096)
			(layers "F.Cu" "F.Mask" "F.Paste")
			(net "PVDDCR_CPU1_P0_VCC5")
		)
		(pad "36" smd rect
			(at -0.64008 -2.899918)
			(size 0.2286 0.6096)
			(layers "F.Cu" "F.Mask" "F.Paste")
			(net "PVDDCR_CPU1_P0_TEMP0")
		)
		(pad "37" smd rect
			(at -1.089914 -2.899918)
			(size 0.2286 0.6096)
			(layers "F.Cu" "F.Mask" "F.Paste")
			(net "PVDDCR_CPU1_P0_LSET5")
		)
		(pad "38" smd rect
			(at -1.540002 -2.899918)
			(size 0.2286 0.6096)
			(layers "F.Cu" "F.Mask" "F.Paste")
			(net "PVDDCR_CPU1_P0_IMON5")
		)
		(pad "39" smd rect
			(at -1.99009 -2.899918)
			(size 0.2286 0.6096)
			(layers "F.Cu" "F.Mask" "F.Paste")
			(net "PVDDCR_CPU1_P0_VCCS")
		)
		(pad "40" smd rect
			(at -0.87503 -1.27508)
			(size 1.7526 1.9558)
			(layers "F.Cu" "F.Mask" "F.Paste")
			(net "GND")
		)
		(pad "41" smd rect
			(at -1.525016 0.249936 270)
			(size 0.3048 0.4572)
			(layers "F.Cu" "F.Mask" "F.Paste")
			(net "NC_PVDDCR_CPU1_P0_GL2_5")
		)
		(zone
			(layer "F.Cu")
			(hatch none 0.5)
			(connect_pads
				(clearance 0)
			)
			(min_thickness 0.25)
			(keepout
				(tracks not_allowed)
				(vias allowed)
				(pads allowed)
				(copperpour not_allowed)
				(footprints allowed)
			)
			(placement
				(enabled no)
				(sheetname "")
			)
			(fill
				(thermal_gap 0.5)
				(thermal_bridge_width 0.5)
				(island_removal_mode 0)
			)
			(polygon
				(pts
					(xy 340.890098 -332.444598) (xy 340.890098 -332.773782) (xy 345.890342 -332.773782) (xy 345.890342 -332.456282)
					(xy 345.60002 -332.456282) (xy 345.60002 -332.480158) (xy 341.18042 -332.480158) (xy 341.18042 -332.444598)
				)
			)
		)
		(zone
			(layer "F.Cu")
			(hatch none 0.5)
			(connect_pads
				(clearance 0)
			)
			(min_thickness 0.25)
			(keepout
				(tracks not_allowed)
				(vias allowed)
				(pads allowed)
				(copperpour not_allowed)
				(footprints allowed)
			)
			(placement
				(enabled no)
				(sheetname "")
			)
			(fill
				(thermal_gap 0.5)
				(thermal_bridge_width 0.5)
				(island_removal_mode 0)
			)
			(polygon
				(pts
					(xy 343.44229 -335.270856) (xy 343.44229 -337.328256) (xy 341.58809 -337.328256) (xy 341.58809 -337.08721)
					(xy 341.345774 -337.08721) (xy 341.345774 -337.568794) (xy 345.109038 -337.568794) (xy 345.109038 -337.383882)
					(xy 343.733628 -337.383882) (xy 343.733628 -335.224882) (xy 345.890342 -335.224882) (xy 345.890342 -334.9752)
					(xy 343.737946 -334.9752)
				)
			)
		)
	)
)
